FILE_TYPE = MACRO_DRAWING;
SET COLOR_WIRE YELLOW;
SET COLOR_PROP ORANGE;
SET COLOR_DOT WHITE;
SET COLOR_ARC YELLOW;
SET COLOR_BODY GREEN;
SET COLOR_NOTE PURPLE;
SET PROP_DISPLAY VALUE;
SET PAGE_NUMBER P189;
FORCEADD QUANTA_TITLE_BLOCK_C..1
(0 0);
FORCEPROP 1 LAST CUSTOM_TXT_CDS <NAME_2>
J 0
(-3175 50);
FORCEPROP 1 LAST CUSTOM_TXT_CDS <NAME_1>
J 0
(-3175 175);
FORCEPROP 1 LAST CUSTOM_TXT_CDS <Q_NUMBER>
J 0
(-1403 103);
DISPLAY 1.212766 (-1403 103);
FORCEPROP 1 LAST CUSTOM_TXT_CDS <Q_PROJ>
J 0
(-2382 102);
DISPLAY 1.212766 (-2382 102);
FORCEPROP 1 LAST CUSTOM_TXT_CDS <Q_REV>
J 0
(-184 103);
DISPLAY 1.212766 (-184 103);
FORCEPROP 1 LAST CUSTOM_TXT_CDS <CON_LAST_MODIFIED>
J 0
(-1885 15);
DISPLAY 0.978723 (-1885 15);
FORCEPROP 1 LAST CUSTOM_TXT_CDS <CON_PAGE_NUM> OF <CON_TOTAL_PAGES>
J 0
(-446 18);
DISPLAY 0.978723 (-446 18);
FORCEPROP 1 LAST Q_TITLE Blank
J 0
(-9366 26);
DISPLAY 2.446809 (-9366 26);
PAINT GREEN (-9366 26);
FORCEPROP 1 LAST CDS_LMAN_SYM_OUTLINE -9475,6775,100,-125
J 0
(0 0);
DISPLAY 0.468085 (0 0);
PAINT GREEN (0 0);
DISPLAY INVISIBLE (0 0);
FORCEPROP 2 LAST CDS_LIB pure_quanta
J 0
(0 0);
DISPLAY INVISIBLE (0 0);
FORCEPROP 2 LAST PAGE_BORDER TRUE
J 0
(-7890 5250);
DISPLAY 0.638298 (-7890 5250);
PAINT PINK (-7890 5250);
DISPLAY INVISIBLE (-7890 5250);
FORCEPROP 2 LAST CDS_XR_PAGE_TITLE CR-214 : @T6G_MB_LIB.T6G(SCH_1):PAGE214
J 0
(-7890 5250);
DISPLAY 0.638298 (-7890 5250);
PAINT PINK (-7890 5250);
DISPLAY INVISIBLE (-7890 5250);
FORCEPROP 2 LAST CUSTOM_TXT_CDS <XR_PAGE_TITLE>
J 0
(-7890 5250);
DISPLAY 0.638298 (-7890 5250);
PAINT PINK (-7890 5250);
DISPLAY INVISIBLE (-7890 5250);
FORCEPROP 1 LAST COMMENT_BODY TRUE
J 0
(12 -13);
DISPLAY 0.978723 (12 -13);
PAINT GREEN (12 -13);
DISPLAY INVISIBLE (12 -13);
FORCEPROP 1 LAST Q_DEPT BU9
J 1
(-3763 49);
DISPLAY 1.957447 (-3763 49);
PAINT GREEN (-3763 49);
DISPLAY INVISIBLE (-3763 49);
FORCEPROP 0 LAST CDS_CON_LAST_MODIFIED Thu Aug 24 10:15:19 2023
J 0
(-1885 15);
DISPLAY INVISIBLE (-1885 15);
QUIT
